(kicad_pcb
	(version 20240108)
	(generator "pcbnew")
	(generator_version "8.0")
	(general
		(thickness 1.62)
		(legacy_teardrops no)
	)
	(paper "A4")
	(title_block
		(title "Jetson Orin Baseboard")
		(date "2025-03-12")
		(rev "1.3.4")
		(company "Antmicro Ltd")
		(comment 1 "www.antmicro.com")
		(comment 9 "footprints 72-74 of 677")
	)
	(layers
		(0 "F.Cu" signal)
		(1 "In1.Cu" signal)
		(2 "In2.Cu" signal)
		(3 "In3.Cu" signal)
		(4 "In4.Cu" jumper)
		(5 "In5.Cu" signal)
		(6 "In6.Cu" signal)
		(31 "B.Cu" signal)
		(32 "B.Adhes" user "B.Adhesive")
		(33 "F.Adhes" user "F.Adhesive")
		(34 "B.Paste" user)
		(35 "F.Paste" user)
		(36 "B.SilkS" user "B.Silkscreen")
		(37 "F.SilkS" user "F.Silkscreen")
		(38 "B.Mask" user)
		(39 "F.Mask" user)
		(40 "Dwgs.User" user "User.Drawings")
		(41 "Cmts.User" user "User.Comments")
		(42 "Eco1.User" user "User.Eco1")
		(43 "Eco2.User" user "User.Eco2")
		(44 "Edge.Cuts" user)
		(45 "Margin" user)
		(46 "B.CrtYd" user "B.Courtyard")
		(47 "F.CrtYd" user "F.Courtyard")
		(48 "B.Fab" user)
		(49 "F.Fab" user)
	)
	(footprint "antmicro-footprints:USB-C_Receptacle_WE_632723300011"
		(layer "F.Cu")
		(at 113.40008 123.835)
		(property "Reference" "J5"
			(at 3.19992 -5.405 0)
			(layer "F.SilkS")
			(effects
				(font
					(size 0.7 0.7)
					(thickness 0.15)
				)
				(justify left bottom)
			)
		)
		(property "Value" "USB-C_WE_632723300011"
			(at 6.03 6.14 90)
			(layer "F.Fab")
			(effects
				(font
					(size 0.7 0.7)
					(thickness 0.15)
				)
				(justify left bottom)
			)
		)
		(property "Footprint" "antmicro-footprints:USB-C_Receptacle_WE_632723300011"
			(at 0 0 0)
			(layer "F.Fab")
			(hide yes)
			(effects
				(font
					(size 1.27 1.27)
					(thickness 0.15)
				)
			)
		)
		(property "Datasheet" "https://www.we-online.com/components/products/datasheet/632723300011.pdf"
			(at 0 0 0)
			(layer "F.Fab")
			(hide yes)
			(effects
				(font
					(size 1.27 1.27)
					(thickness 0.15)
				)
			)
		)
		(property "Author" "Antmicro"
			(at 0 0 0)
			(layer "F.Fab")
			(hide yes)
			(effects
				(font
					(size 1 1)
					(thickness 0.15)
				)
			)
		)
		(property "License" "Apache-2.0"
			(at 0 0 0)
			(layer "F.Fab")
			(hide yes)
			(effects
				(font
					(size 1 1)
					(thickness 0.15)
				)
			)
		)
		(property "MPN" "632723300011"
			(at 0 0 0)
			(layer "F.Fab")
			(hide yes)
			(effects
				(font
					(size 1 1)
					(thickness 0.15)
				)
			)
		)
		(property "Manufacturer" "Würth Elektronik"
			(at 0 0 0)
			(layer "F.Fab")
			(hide yes)
			(effects
				(font
					(size 1 1)
					(thickness 0.15)
				)
			)
		)
		(sheetname "USB3")
		(sheetfile "usb3.kicad_sch")
		(attr smd)
		(fp_line
			(start -4.4 -4.899)
			(end -4.4 -4.2)
			(stroke
				(width 0.15)
				(type solid)
			)
			(layer "F.SilkS")
		)
		(fp_line
			(start -4.4 -4.899)
			(end -2.999 -4.899)
			(stroke
				(width 0.15)
				(type solid)
			)
			(layer "F.SilkS")
		)
		(fp_line
			(start -4.4 -2.2)
			(end -4.4 0.6)
			(stroke
				(width 0.15)
				(type solid)
			)
			(layer "F.SilkS")
		)
		(fp_line
			(start -4.4 2.4)
			(end -4.4 3.201)
			(stroke
				(width 0.15)
				(type solid)
			)
			(layer "F.SilkS")
		)
		(fp_line
			(start 3 -4.899)
			(end 4.401 -4.899)
			(stroke
				(width 0.15)
				(type solid)
			)
			(layer "F.SilkS")
		)
		(fp_line
			(start 4.401 -4.2)
			(end 4.401 -4.899)
			(stroke
				(width 0.15)
				(type solid)
			)
			(layer "F.SilkS")
		)
		(fp_line
			(start 4.401 -2.2)
			(end 4.401 0.6)
			(stroke
				(width 0.15)
				(type solid)
			)
			(layer "F.SilkS")
		)
		(fp_line
			(start 4.401 2.4)
			(end 4.401 3.201)
			(stroke
				(width 0.15)
				(type solid)
			)
			(layer "F.SilkS")
		)
		(fp_circle
			(center -3.299 -5.598)
			(end -3.249 -5.598)
			(stroke
				(width 0.15)
				(type solid)
			)
			(fill solid)
			(layer "F.SilkS")
		)
		(fp_line
			(start -4.9 -5.4)
			(end -3.4 -5.4)
			(stroke
				(width 0.05)
				(type solid)
			)
			(layer "F.CrtYd")
		)
		(fp_line
			(start -4.9 6.5)
			(end -4.9 -5.4)
			(stroke
				(width 0.05)
				(type solid)
			)
			(layer "F.CrtYd")
		)
		(fp_line
			(start -3.4 -6.6)
			(end 3.4 -6.6)
			(stroke
				(width 0.05)
				(type solid)
			)
			(layer "F.CrtYd")
		)
		(fp_line
			(start -3.4 -5.4)
			(end -3.4 -6.6)
			(stroke
				(width 0.05)
				(type solid)
			)
			(layer "F.CrtYd")
		)
		(fp_line
			(start 3.4 -6.6)
			(end 3.4 -5.4)
			(stroke
				(width 0.05)
				(type solid)
			)
			(layer "F.CrtYd")
		)
		(fp_line
			(start 3.4 -5.4)
			(end 4.9 -5.4)
			(stroke
				(width 0.05)
				(type solid)
			)
			(layer "F.CrtYd")
		)
		(fp_line
			(start 4.9 -5.4)
			(end 4.9 6.5)
			(stroke
				(width 0.05)
				(type solid)
			)
			(layer "F.CrtYd")
		)
		(fp_line
			(start 4.9 6.5)
			(end -4.9 6.5)
			(stroke
				(width 0.05)
				(type solid)
			)
			(layer "F.CrtYd")
		)
		(fp_line
			(start -4.499 -5)
			(end -4.499 6.001)
			(stroke
				(width 0.15)
				(type solid)
			)
			(layer "F.Fab")
		)
		(fp_line
			(start -4.499 6.001)
			(end 4.499 6.001)
			(stroke
				(width 0.15)
				(type solid)
			)
			(layer "F.Fab")
		)
		(fp_line
			(start -2.999 -6.3)
			(end -2.999 -5)
			(stroke
				(width 0.15)
				(type solid)
			)
			(layer "F.Fab")
		)
		(fp_line
			(start -2.999 -5)
			(end -4.499 -5)
			(stroke
				(width 0.15)
				(type solid)
			)
			(layer "F.Fab")
		)
		(fp_line
			(start -2.979 -6.158)
			(end -2.859 -6.278)
			(stroke
				(width 0.15)
				(type solid)
			)
			(layer "F.Fab")
		)
		(fp_line
			(start 3 -6.3)
			(end -2.999 -6.3)
			(stroke
				(width 0.15)
				(type solid)
			)
			(layer "F.Fab")
		)
		(fp_line
			(start 3 -5)
			(end 3 -6.3)
			(stroke
				(width 0.15)
				(type solid)
			)
			(layer "F.Fab")
		)
		(fp_line
			(start 4.499 -5)
			(end 3 -5)
			(stroke
				(width 0.15)
				(type solid)
			)
			(layer "F.Fab")
		)
		(fp_line
			(start 4.499 6.001)
			(end 4.499 -5)
			(stroke
				(width 0.15)
				(type solid)
			)
			(layer "F.Fab")
		)
		(fp_text user "License: Apache-2.0"
			(at -5.272 8.495 0)
			(layer "F.Fab")
			(hide yes)
			(effects
				(font
					(size 0.7 0.7)
					(thickness 0.15)
				)
				(justify left bottom)
			)
		)
		(fp_text user "Author: Antmicro"
			(at -5.272 10.895 0)
			(layer "F.Fab")
			(hide yes)
			(effects
				(font
					(size 0.7 0.7)
					(thickness 0.15)
				)
				(justify left bottom)
			)
		)
		(fp_text user "${REFERENCE}"
			(at -5.272 9.695 0)
			(layer "F.Fab")
			(hide yes)
			(effects
				(font
					(size 0.7 0.7)
					(thickness 0.15)
				)
				(justify left bottom)
			)
		)
		(pad "" smd roundrect
			(at 0 -1.055)
			(size 0.2 1)
			(layers "F.Cu" "F.Paste" "F.Mask")
			(roundrect_rratio 0.25)
		)
		(pad "" smd roundrect
			(at 0 2.045)
			(size 0.2 1)
			(layers "F.Cu" "F.Paste" "F.Mask")
			(roundrect_rratio 0.25)
		)
		(pad "A1" smd roundrect
			(at -2.75 -5.635)
			(size 0.3 1.2)
			(layers "F.Cu" "F.Paste" "F.Mask")
			(roundrect_rratio 0.25)
			(net 1 "GND")
			(pinfunction "GND")
			(pintype "power_in")
		)
		(pad "A2" smd roundrect
			(at -2.25 -5.635)
			(size 0.3 1.2)
			(layers "F.Cu" "F.Paste" "F.Mask")
			(roundrect_rratio 0.25)
			(net 265 "/USB3/USBC1_CONN_TX1_N")
			(pinfunction "TX_{1}+")
			(pintype "bidirectional")
		)
		(pad "A3" smd roundrect
			(at -1.75 -5.635)
			(size 0.3 1.2)
			(layers "F.Cu" "F.Paste" "F.Mask")
			(roundrect_rratio 0.25)
			(net 267 "/USB3/USBC1_CONN_TX1_P")
			(pinfunction "TX_{1}-")
			(pintype "bidirectional")
		)
		(pad "A4" smd roundrect
			(at -1.25 -5.635)
			(size 0.3 1.2)
			(layers "F.Cu" "F.Paste" "F.Mask")
			(roundrect_rratio 0.25)
			(net 270 "/USB3/USBC1_VBUS")
			(pinfunction "VBUS")
			(pintype "passive")
		)
		(pad "A5" smd roundrect
			(at -0.75 -5.635)
			(size 0.3 1.2)
			(layers "F.Cu" "F.Paste" "F.Mask")
			(roundrect_rratio 0.25)
			(net 282 "/USB3/USBC1_CC1")
			(pinfunction "CC_{1}")
			(pintype "bidirectional")
		)
		(pad "A6" smd roundrect
			(at -0.25 -5.635)
			(size 0.3 1.2)
			(layers "F.Cu" "F.Paste" "F.Mask")
			(roundrect_rratio 0.25)
			(net 433 "USB0_D_P")
			(pinfunction "D_{A}+")
			(pintype "bidirectional")
		)
		(pad "A7" smd roundrect
			(at 0.25 -5.635)
			(size 0.3 1.2)
			(layers "F.Cu" "F.Paste" "F.Mask")
			(roundrect_rratio 0.25)
			(net 40 "USB0_D_N")
			(pinfunction "D_{A}-")
			(pintype "bidirectional")
		)
		(pad "A8" smd roundrect
			(at 0.75 -5.635)
			(size 0.3 1.2)
			(layers "F.Cu" "F.Paste" "F.Mask")
			(roundrect_rratio 0.25)
			(net 548 "unconnected-(J5-SBU_{1}-PadA8)")
			(pinfunction "SBU_{1}")
			(pintype "bidirectional+no_connect")
		)
		(pad "A9" smd roundrect
			(at 1.25 -5.635)
			(size 0.3 1.2)
			(layers "F.Cu" "F.Paste" "F.Mask")
			(roundrect_rratio 0.25)
			(net 270 "/USB3/USBC1_VBUS")
			(pinfunction "VBUS")
			(pintype "passive")
		)
		(pad "A10" smd roundrect
			(at 1.75 -5.635)
			(size 0.3 1.2)
			(layers "F.Cu" "F.Paste" "F.Mask")
			(roundrect_rratio 0.25)
			(net 369 "/USB3/USBC1_RX2_N")
			(pinfunction "RX_{2}-")
			(pintype "bidirectional")
		)
		(pad "A11" smd roundrect
			(at 2.25 -5.635)
			(size 0.3 1.2)
			(layers "F.Cu" "F.Paste" "F.Mask")
			(roundrect_rratio 0.25)
			(net 390 "/USB3/USBC1_RX2_P")
			(pinfunction "RX_{2}+")
			(pintype "bidirectional")
		)
		(pad "A12" smd roundrect
			(at 2.75 -5.635)
			(size 0.3 1.2)
			(layers "F.Cu" "F.Paste" "F.Mask")
			(roundrect_rratio 0.25)
			(net 1 "GND")
			(pinfunction "GND")
			(pintype "passive")
		)
		(pad "B1" thru_hole circle
			(at 2.8 -4.385)
			(size 0.65 0.65)
			(drill 0.3)
			(layers "*.Cu" "*.Mask")
			(remove_unused_layers no)
			(net 1 "GND")
			(pinfunction "GND")
			(pintype "passive")
		)
		(pad "B2" thru_hole circle
			(at 2.4 -3.685)
			(size 0.65 0.65)
			(drill 0.3)
			(layers "*.Cu" "*.Mask")
			(remove_unused_layers no)
			(net 263 "/USB3/USBC1_CONN_TX2_N")
			(pinfunction "TX_{2}+")
			(pintype "bidirectional")
		)
		(pad "B3" thru_hole circle
			(at 1.6 -3.685)
			(size 0.65 0.65)
			(drill 0.3)
			(layers "*.Cu" "*.Mask")
			(remove_unused_layers no)
			(net 269 "/USB3/USBC1_CONN_TX2_P")
			(pinfunction "TX_{2}-")
			(pintype "bidirectional")
		)
		(pad "B4" thru_hole circle
			(at 1.2 -4.385)
			(size 0.65 0.65)
			(drill 0.3)
			(layers "*.Cu" "*.Mask")
			(remove_unused_layers no)
			(net 270 "/USB3/USBC1_VBUS")
			(pinfunction "VBUS")
			(pintype "passive")
		)
		(pad "B5" thru_hole circle
			(at 0.8 -3.685)
			(size 0.65 0.65)
			(drill 0.3)
			(layers "*.Cu" "*.Mask")
			(remove_unused_layers no)
			(net 283 "/USB3/USBC1_CC2")
			(pinfunction "CC_{2}")
			(pintype "bidirectional")
		)
		(pad "B6" thru_hole circle
			(at 0.4 -4.385)
			(size 0.65 0.65)
			(drill 0.3)
			(layers "*.Cu" "*.Mask")
			(remove_unused_layers no)
			(net 433 "USB0_D_P")
			(pinfunction "D_{B}+")
			(pintype "bidirectional")
		)
		(pad "B7" thru_hole circle
			(at -0.4 -4.385)
			(size 0.65 0.65)
			(drill 0.3)
			(layers "*.Cu" "*.Mask")
			(remove_unused_layers no)
			(net 40 "USB0_D_N")
			(pinfunction "D_{B}-")
			(pintype "bidirectional")
		)
		(pad "B8" thru_hole circle
			(at -0.8 -3.685)
			(size 0.65 0.65)
			(drill 0.3)
			(layers "*.Cu" "*.Mask")
			(remove_unused_layers no)
			(net 550 "unconnected-(J5-SBU_{2}-PadB8)")
			(pinfunction "SBU_{2}")
			(pintype "bidirectional+no_connect")
		)
		(pad "B9" thru_hole circle
			(at -1.2 -4.385)
			(size 0.65 0.65)
			(drill 0.3)
			(layers "*.Cu" "*.Mask")
			(remove_unused_layers no)
			(net 270 "/USB3/USBC1_VBUS")
			(pinfunction "VBUS")
			(pintype "passive")
		)
		(pad "B10" thru_hole circle
			(at -1.6 -3.685)
			(size 0.65 0.65)
			(drill 0.3)
			(layers "*.Cu" "*.Mask")
			(remove_unused_layers no)
			(net 366 "/USB3/USBC1_RX1_N")
			(pinfunction "RX_{1}-")
			(pintype "bidirectional")
		)
		(pad "B11" thru_hole circle
			(at -2.4 -3.685)
			(size 0.65 0.65)
			(drill 0.3)
			(layers "*.Cu" "*.Mask")
			(remove_unused_layers no)
			(net 368 "/USB3/USBC1_RX1_P")
			(pinfunction "RX_{1}+")
			(pintype "bidirectional")
		)
		(pad "B12" thru_hole circle
			(at -2.8 -4.385)
			(size 0.65 0.65)
			(drill 0.3)
			(layers "*.Cu" "*.Mask")
			(remove_unused_layers no)
			(net 1 "GND")
			(pinfunction "GND")
			(pintype "passive")
		)
		(pad "SH" thru_hole oval
			(at -4.27 -3.235)
			(size 1 1.6)
			(drill oval 0.6 1.2)
			(layers "*.Cu" "*.Mask")
			(remove_unused_layers no)
			(net 1 "GND")
			(pinfunction "SH")
			(pintype "passive")
		)
		(pad "SH" thru_hole oval
			(at -4.27 1.495)
			(size 1 1.6)
			(drill oval 0.6 1.2)
			(layers "*.Cu" "*.Mask")
			(remove_unused_layers no)
			(net 1 "GND")
			(pinfunction "SH")
			(pintype "passive")
		)
		(pad "SH" thru_hole circle
			(at -2 -4.385)
			(size 0.65 0.65)
			(drill 0.3)
			(layers "*.Cu" "*.Mask")
			(remove_unused_layers no)
			(net 1 "GND")
			(pinfunction "SH")
			(pintype "passive")
		)
		(pad "SH" thru_hole circle
			(at 2 -4.385)
			(size 0.65 0.65)
			(drill 0.3)
			(layers "*.Cu" "*.Mask")
			(remove_unused_layers no)
			(net 1 "GND")
			(pinfunction "SH")
			(pintype "passive")
		)
		(pad "SH" thru_hole oval
			(at 4.27 -3.235)
			(size 1 1.6)
			(drill oval 0.6 1.2)
			(layers "*.Cu" "*.Mask")
			(remove_unused_layers no)
			(net 1 "GND")
			(pinfunction "SH")
			(pintype "passive")
		)
		(pad "SH" thru_hole oval
			(at 4.27 1.495)
			(size 1 1.6)
			(drill oval 0.6 1.2)
			(layers "*.Cu" "*.Mask")
			(remove_unused_layers no)
			(net 1 "GND")
			(pinfunction "SH")
			(pintype "passive")
		)
	)
	(footprint "antmicro-footprints:C_0402_1005Metric"
		(layer "F.Cu")
		(at 89.3 117.95 90)
		(descr "Capacitor SMD 0402")
		(tags "capacitor SMD 0402")
		(property "Reference" "C164"
			(at -1.03 -0.45 90)
			(layer "F.SilkS")
			(effects
				(font
					(size 0.7 0.7)
					(thickness 0.15)
				)
				(justify left bottom)
			)
		)
		(property "Value" "C_100n_0402"
			(at 0 1.4 90)
			(layer "F.Fab")
			(effects
				(font
					(size 0.7 0.7)
					(thickness 0.15)
				)
				(justify left bottom)
			)
		)
		(property "Footprint" "antmicro-footprints:C_0402_1005Metric"
			(at 0 0 90)
			(layer "F.Fab")
			(hide yes)
			(effects
				(font
					(size 1.27 1.27)
					(thickness 0.15)
				)
			)
		)
		(property "Datasheet" "https://www.murata.com/products/productdetail?partno=GRM155R61H104KE14%23"
			(at 0 0 90)
			(layer "F.Fab")
			(hide yes)
			(effects
				(font
					(size 1.27 1.27)
					(thickness 0.15)
				)
			)
		)
		(property "Author" "Antmicro"
			(at 207.25 28.65 0)
			(layer "F.Fab")
			(hide yes)
			(effects
				(font
					(size 1 1)
					(thickness 0.15)
				)
			)
		)
		(property "Dielectric" "X5R"
			(at 207.25 28.65 0)
			(layer "F.Fab")
			(hide yes)
			(effects
				(font
					(size 1 1)
					(thickness 0.15)
				)
			)
		)
		(property "License" "Apache-2.0"
			(at 207.25 28.65 0)
			(layer "F.Fab")
			(hide yes)
			(effects
				(font
					(size 1 1)
					(thickness 0.15)
				)
			)
		)
		(property "MPN" "GRM155R61H104KE14D"
			(at 207.25 28.65 0)
			(layer "F.Fab")
			(hide yes)
			(effects
				(font
					(size 1 1)
					(thickness 0.15)
				)
			)
		)
		(property "Manufacturer" "Murata"
			(at 207.25 28.65 0)
			(layer "F.Fab")
			(hide yes)
			(effects
				(font
					(size 1 1)
					(thickness 0.15)
				)
			)
		)
		(property "Val" "100n"
			(at 207.25 28.65 0)
			(layer "F.Fab")
			(hide yes)
			(effects
				(font
					(size 1 1)
					(thickness 0.15)
				)
			)
		)
		(property "Voltage" "50V"
			(at 207.25 28.65 0)
			(layer "F.Fab")
			(hide yes)
			(effects
				(font
					(size 1 1)
					(thickness 0.15)
				)
			)
		)
		(sheetname "HDMI")
		(sheetfile "hdmi.kicad_sch")
		(attr smd)
		(fp_rect
			(start -0.925 -0.47)
			(end 0.925 0.47)
			(stroke
				(width 0.05)
				(type default)
			)
			(fill none)
			(layer "F.CrtYd")
		)
		(fp_line
			(start 0.504 -0.25)
			(end 0.504 0.248)
			(stroke
				(width 0.15)
				(type solid)
			)
			(layer "F.Fab")
		)
		(fp_line
			(start -0.494 -0.25)
			(end 0.504 -0.25)
			(stroke
				(width 0.15)
				(type solid)
			)
			(layer "F.Fab")
		)
		(fp_line
			(start 0.504 0.248)
			(end -0.494 0.248)
			(stroke
				(width 0.15)
				(type solid)
			)
			(layer "F.Fab")
		)
		(fp_line
			(start -0.494 0.248)
			(end -0.494 -0.25)
			(stroke
				(width 0.15)
				(type solid)
			)
			(layer "F.Fab")
		)
		(fp_text user "Author: Antmicro"
			(at -0.932 4.17 90)
			(layer "F.Fab")
			(hide yes)
			(effects
				(font
					(size 0.7 0.7)
					(thickness 0.15)
				)
				(justify left bottom)
			)
		)
		(fp_text user "License: Apache-2.0"
			(at -0.932 5.17 90)
			(layer "F.Fab")
			(hide yes)
			(effects
				(font
					(size 0.7 0.7)
					(thickness 0.15)
				)
				(justify left bottom)
			)
		)
		(fp_text user "${REFERENCE}"
			(at -0.932 3.168 90)
			(layer "F.Fab")
			(hide yes)
			(effects
				(font
					(size 0.7 0.7)
					(thickness 0.15)
				)
				(justify left bottom)
			)
		)
		(pad "1" smd roundrect
			(at -0.48 0 90)
			(size 0.59 0.64)
			(layers "F.Cu" "F.Paste" "F.Mask")
			(roundrect_rratio 0.25)
			(net 1 "GND")
			(pintype "passive")
		)
		(pad "2" smd roundrect
			(at 0.48 0 90)
			(size 0.59 0.64)
			(layers "F.Cu" "F.Paste" "F.Mask")
			(roundrect_rratio 0.25)
			(net 498 "/HDMI/5V_HDMI")
			(pintype "passive")
		)
	)
	(footprint "antmicro-footprints:Fiducial_1mm_Mask2mm"
		(layer "F.Cu")
		(at 31.6 70.35)
		(descr "Circular Fiducial, 1mm bare copper, 3mm soldermask opening")
		(tags "fiducial")
		(property "Reference" "FID2"
			(at 0 -1.4 0)
			(layer "F.SilkS")
			(hide yes)
			(effects
				(font
					(size 0.7 0.7)
					(thickness 0.15)
				)
				(justify left bottom)
			)
		)
		(property "Value" "Fiducial_1mm_Mask2mm"
			(at 0 2.2 0)
			(layer "F.Fab")
			(effects
				(font
					(size 0.7 0.7)
					(thickness 0.15)
				)
				(justify left bottom)
			)
		)
		(property "Footprint" "antmicro-footprints:Fiducial_1mm_Mask2mm"
			(at 0 0 0)
			(layer "F.Fab")
			(hide yes)
			(effects
				(font
					(size 1.27 1.27)
					(thickness 0.15)
				)
			)
		)
		(attr board_only exclude_from_pos_files exclude_from_bom)
		(fp_circle
			(center 0 0)
			(end 1.24 0)
			(stroke
				(width 0.05)
				(type solid)
			)
			(fill none)
			(layer "F.CrtYd")
		)
		(fp_circle
			(center 0 0)
			(end 0.999 0)
			(stroke
				(width 0.15)
				(type solid)
			)
			(fill none)
			(layer "F.Fab")
		)
		(fp_text user "License: Apache-2.0"
			(at -1.25 7.003 0)
			(layer "F.Fab")
			(hide yes)
			(effects
				(font
					(size 0.7 0.7)
					(thickness 0.15)
				)
				(justify left bottom)
			)
		)
		(fp_text user "${REFERENCE}"
			(at -1.25 4.603 0)
			(layer "F.Fab")
			(hide yes)
			(effects
				(font
					(size 0.7 0.7)
					(thickness 0.15)
				)
				(justify left bottom)
			)
		)
		(fp_text user "Author: Antmicro"
			(at -1.25 5.803 0)
			(layer "F.Fab")
			(hide yes)
			(effects
				(font
					(size 0.7 0.7)
					(thickness 0.15)
				)
				(justify left bottom)
			)
		)
		(pad "" smd circle
			(at 0 0)
			(size 1 1)
			(layers "F.Cu" "F.Mask")
			(solder_mask_margin 0.5)
			(clearance 0.5)
		)
	)
)
